(kicad_pcb
	(version 20260206)
	(generator "pcbnew")
	(generator_version "10.0")
	(general
		(thickness 1.6)
		(legacy_teardrops no)
	)
	(paper "A4")
	(title_block
		(title "Bryce Canyon_IOM_M2_16342-2_OCP.brd")
		(comment 1 "Bryce Canyon / footprints 851-858 of 1146")
	)
	(layers
		(0 "F.Cu" signal "TOP")
		(4 "In1.Cu" signal "L2GND")
		(6 "In2.Cu" signal "L3")
		(8 "In3.Cu" signal "L4VCC")
		(10 "In4.Cu" signal "L5VCC")
		(12 "In5.Cu" signal "L6")
		(14 "In6.Cu" signal "L7GND")
		(2 "B.Cu" signal "BOTTOM")
		(9 "F.Adhes" user "F.Adhesive")
		(11 "B.Adhes" user "B.Adhesive")
		(13 "F.Paste" user "Package Geometry/Pastemask Top")
		(15 "B.Paste" user "Package Geometry/Pastemask Bottom")
		(5 "F.SilkS" user "Ref Des/Silkscreen Top")
		(7 "B.SilkS" user "Ref Des/Silkscreen Bottom")
		(1 "F.Mask" user "Board Geometry/Soldermask Top")
		(3 "B.Mask" user "Board Geometry/Soldermask Bottom")
		(17 "Dwgs.User" user "User.Drawings")
		(19 "Cmts.User" user "User.Comments")
		(21 "Eco1.User" user "User.Eco1")
		(23 "Eco2.User" user "User.Eco2")
		(25 "Edge.Cuts" user "Board Geometry/Outline")
		(27 "Margin" user)
		(31 "F.CrtYd" user "Package Geometry/Place Bound Top")
		(29 "B.CrtYd" user "Package Geometry/Place Bound Bottom")
		(35 "F.Fab" user "Ref Des/Assembly Top")
		(33 "B.Fab" user "Ref Des/Assembly Bottom")
	)
	(footprint ""
		(layer "B.Cu")
		(at 221.94266 -56.533542 -90)
		(property "Reference" "R464"
			(at 0 0 90)
			(layer "B.SilkS")
			(hide yes)
			(effects
				(font
					(size 1.27 1.27)
				)
				(justify mirror)
			)
		)
		(property "Value" "2D2R3-1-U-GP"
			(at 0.0254 -2.5146 270)
			(unlocked yes)
			(layer "B.Fab")
			(hide yes)
			(effects
				(font
					(size 1.016 1.016)
					(thickness 0.1524)
				)
				(justify mirror)
			)
		)
		(property "Device Type" "R603H22"
			(at 0.0254 -4.0386 270)
			(unlocked yes)
			(layer "B.Fab")
			(hide yes)
			(effects
				(font
					(size 1.016 1.016)
					(thickness 0.1524)
				)
				(justify mirror)
			)
		)
		(duplicate_pad_numbers_are_jumpers no)
		(fp_line
			(start -0.2032 0)
			(end -0.4826 0)
			(stroke
				(width 0.2032)
				(type default)
			)
			(layer "B.SilkS")
		)
		(fp_line
			(start 0.4826 0)
			(end 0.2032 0)
			(stroke
				(width 0.2032)
				(type default)
			)
			(layer "B.SilkS")
		)
		(fp_rect
			(start 0.5842 1.3335)
			(end -0.5842 -1.3335)
			(stroke
				(width 0)
				(type default)
			)
			(fill no)
			(layer "B.CrtYd")
		)
		(fp_rect
			(start 0.5842 1.3335)
			(end -0.5842 -1.3335)
			(stroke
				(width 0)
				(type default)
			)
			(fill no)
			(layer "B.Fab")
		)
		(pad "1" smd custom
			(at 0 -0.762 90)
			(size 0.2159 0.2159)
			(layers "B.Cu" "B.Mask" "B.Paste")
			(net "P12V_STBY")
			(options
				(clearance outline)
				(anchor circle)
			)
			(primitives
				(gr_poly
					(pts
						(arc
							(start -0.3302 0.4318)
							(mid -0.402042 0.402042)
							(end -0.4318 0.3302)
						)
						(arc
							(start -0.4318 -0.3302)
							(mid -0.402042 -0.402042)
							(end -0.3302 -0.4318)
						)
						(arc
							(start 0.3302 -0.4318)
							(mid 0.402042 -0.402042)
							(end 0.4318 -0.3302)
						)
						(arc
							(start 0.4318 0.3302)
							(mid 0.402042 0.402042)
							(end 0.3302 0.4318)
						)
					)
					(width 0)
					(fill yes)
				)
			)
		)
		(pad "2" smd custom
			(at 0 0.762 90)
			(size 0.2159 0.2159)
			(layers "B.Cu" "B.Mask" "B.Paste")
			(net "P5V_VDD")
			(options
				(clearance outline)
				(anchor circle)
			)
			(primitives
				(gr_poly
					(pts
						(arc
							(start -0.3302 0.4318)
							(mid -0.402042 0.402042)
							(end -0.4318 0.3302)
						)
						(arc
							(start -0.4318 -0.3302)
							(mid -0.402042 -0.402042)
							(end -0.3302 -0.4318)
						)
						(arc
							(start 0.3302 -0.4318)
							(mid 0.402042 -0.402042)
							(end 0.4318 -0.3302)
						)
						(arc
							(start 0.4318 0.3302)
							(mid 0.402042 0.402042)
							(end 0.3302 0.4318)
						)
					)
					(width 0)
					(fill yes)
				)
			)
		)
	)
	(footprint ""
		(layer "B.Cu")
		(at 13.2207 -147.3835 -90)
		(property "Reference" "C62"
			(at 0 0 90)
			(layer "B.SilkS")
			(hide yes)
			(effects
				(font
					(size 1.27 1.27)
				)
				(justify mirror)
			)
		)
		(property "Value" "SC1U16V3KX-5GP"
			(at 0 -2.8194 270)
			(unlocked yes)
			(layer "B.Fab")
			(hide yes)
			(effects
				(font
					(size 1.016 1.016)
					(thickness 0.1524)
				)
				(justify mirror)
			)
		)
		(property "Device Type" "C603H36"
			(at 0 -4.3434 270)
			(unlocked yes)
			(layer "B.Fab")
			(hide yes)
			(effects
				(font
					(size 1.016 1.016)
					(thickness 0.1524)
				)
				(justify mirror)
			)
		)
		(duplicate_pad_numbers_are_jumpers no)
		(fp_line
			(start -0.508 0)
			(end 0.508 0)
			(stroke
				(width 0.2032)
				(type default)
			)
			(layer "B.SilkS")
		)
		(fp_rect
			(start 0.5842 1.3335)
			(end -0.5842 -1.3335)
			(stroke
				(width 0)
				(type default)
			)
			(fill no)
			(layer "B.CrtYd")
		)
		(fp_rect
			(start 0.5842 1.3335)
			(end -0.5842 -1.3335)
			(stroke
				(width 0)
				(type default)
			)
			(fill no)
			(layer "B.Fab")
		)
		(pad "1" smd custom
			(at 0 -0.762 90)
			(size 0.2159 0.2159)
			(layers "B.Cu" "B.Mask" "B.Paste")
			(net "P1V2_STBY")
			(options
				(clearance outline)
				(anchor circle)
			)
			(primitives
				(gr_poly
					(pts
						(arc
							(start -0.3302 0.4318)
							(mid -0.402042 0.402042)
							(end -0.4318 0.3302)
						)
						(arc
							(start -0.4318 -0.3302)
							(mid -0.402042 -0.402042)
							(end -0.3302 -0.4318)
						)
						(arc
							(start 0.3302 -0.4318)
							(mid 0.402042 -0.402042)
							(end 0.4318 -0.3302)
						)
						(arc
							(start 0.4318 0.3302)
							(mid 0.402042 0.402042)
							(end 0.3302 0.4318)
						)
					)
					(width 0)
					(fill yes)
				)
			)
		)
		(pad "2" smd custom
			(at 0 0.762 90)
			(size 0.2159 0.2159)
			(layers "B.Cu" "B.Mask" "B.Paste")
			(net "GND")
			(options
				(clearance outline)
				(anchor circle)
			)
			(primitives
				(gr_poly
					(pts
						(arc
							(start -0.3302 0.4318)
							(mid -0.402042 0.402042)
							(end -0.4318 0.3302)
						)
						(arc
							(start -0.4318 -0.3302)
							(mid -0.402042 -0.402042)
							(end -0.3302 -0.4318)
						)
						(arc
							(start 0.3302 -0.4318)
							(mid 0.402042 -0.402042)
							(end 0.4318 -0.3302)
						)
						(arc
							(start 0.4318 0.3302)
							(mid 0.402042 0.402042)
							(end 0.3302 0.4318)
						)
					)
					(width 0)
					(fill yes)
				)
			)
		)
	)
	(footprint ""
		(layer "B.Cu")
		(at 44.5008 -140.97)
		(property "Reference" "TP28"
			(at 0 0 0)
			(layer "B.SilkS")
			(hide yes)
			(effects
				(font
					(size 1.27 1.27)
				)
				(justify mirror)
			)
		)
		(property "Value" "TPAD28-2-GP"
			(at 0.0127 -1.6637 0)
			(unlocked yes)
			(layer "B.Fab")
			(hide yes)
			(effects
				(font
					(size 1.016 1.016)
					(thickness 0.1524)
				)
				(justify mirror)
			)
		)
		(property "Device Type" "TPAD28"
			(at 0.0127 -3.1877 0)
			(unlocked yes)
			(layer "B.Fab")
			(hide yes)
			(effects
				(font
					(size 1.016 1.016)
					(thickness 0.1524)
				)
				(justify mirror)
			)
		)
		(duplicate_pad_numbers_are_jumpers no)
		(fp_poly
			(pts
				(arc
					(start 0.3556 0)
					(mid -0.3556 0)
					(end 0.3556 0)
				)
			)
			(stroke
				(width 0)
				(type default)
			)
			(fill no)
			(layer "B.CrtYd")
		)
		(fp_poly
			(pts
				(arc
					(start 0.6096 0)
					(mid -0.6096 0)
					(end 0.6096 0)
				)
			)
			(stroke
				(width 0)
				(type default)
			)
			(fill no)
			(layer "B.Fab")
		)
		(pad "1" smd circle
			(at 0 0 180)
			(size 0.7112 0.7112)
			(layers "B.Cu" "B.Mask" "B.Paste")
			(net "TP_BMC_GPIOR2")
		)
	)
	(footprint ""
		(layer "B.Cu")
		(at 204.93355 -107.29341)
		(property "Reference" "C631"
			(at 0 0 0)
			(layer "B.SilkS")
			(hide yes)
			(effects
				(font
					(size 1.27 1.27)
				)
				(justify mirror)
			)
		)
		(property "Value" "SCD1U16V2KX-3GP"
			(at -1.1811 -2.7051 0)
			(unlocked yes)
			(layer "B.Fab")
			(hide yes)
			(effects
				(font
					(size 1.016 1.016)
					(thickness 0.1524)
				)
				(justify mirror)
			)
		)
		(property "Device Type" "C402H22"
			(at -1.1811 -4.2291 0)
			(unlocked yes)
			(layer "B.Fab")
			(hide yes)
			(effects
				(font
					(size 1.016 1.016)
					(thickness 0.1524)
				)
				(justify mirror)
			)
		)
		(duplicate_pad_numbers_are_jumpers no)
		(fp_rect
			(start 0.4318 0.9525)
			(end -0.4318 -0.9525)
			(stroke
				(width 0)
				(type default)
			)
			(fill no)
			(layer "B.CrtYd")
		)
		(fp_rect
			(start 0.4318 0.9525)
			(end -0.4318 -0.9525)
			(stroke
				(width 0)
				(type default)
			)
			(fill no)
			(layer "B.Fab")
		)
		(pad "1" smd custom
			(at 0 -0.4445 180)
			(size 0.1524 0.1524)
			(layers "B.Cu" "B.Mask" "B.Paste")
			(net "P1V8_STBY")
			(options
				(clearance outline)
				(anchor circle)
			)
			(primitives
				(gr_poly
					(pts
						(arc
							(start 0.3048 0.2032)
							(mid 0.275042 0.275042)
							(end 0.2032 0.3048)
						)
						(arc
							(start -0.2032 0.3048)
							(mid -0.275042 0.275042)
							(end -0.3048 0.2032)
						)
						(arc
							(start -0.3048 -0.2032)
							(mid -0.275042 -0.275042)
							(end -0.2032 -0.3048)
						)
						(arc
							(start 0.2032 -0.3048)
							(mid 0.275042 -0.275042)
							(end 0.3048 -0.2032)
						)
					)
					(width 0)
					(fill yes)
				)
			)
		)
		(pad "2" smd custom
			(at 0 0.4445 180)
			(size 0.1524 0.1524)
			(layers "B.Cu" "B.Mask" "B.Paste")
			(net "GND")
			(options
				(clearance outline)
				(anchor circle)
			)
			(primitives
				(gr_poly
					(pts
						(arc
							(start 0.3048 0.2032)
							(mid 0.275042 0.275042)
							(end 0.2032 0.3048)
						)
						(arc
							(start -0.2032 0.3048)
							(mid -0.275042 0.275042)
							(end -0.3048 0.2032)
						)
						(arc
							(start -0.3048 -0.2032)
							(mid -0.275042 -0.275042)
							(end -0.2032 -0.3048)
						)
						(arc
							(start 0.2032 -0.3048)
							(mid 0.275042 -0.275042)
							(end 0.3048 -0.2032)
						)
					)
					(width 0)
					(fill yes)
				)
			)
		)
	)
	(footprint ""
		(layer "B.Cu")
		(at 41.3258 -125.476 180)
		(property "Reference" "R362"
			(at 0 0 0)
			(layer "B.SilkS")
			(hide yes)
			(effects
				(font
					(size 1.27 1.27)
				)
				(justify mirror)
			)
		)
		(property "Value" "4K7R2F-GP"
			(at -0.064008 -3.993896 180)
			(unlocked yes)
			(layer "B.Fab")
			(hide yes)
			(effects
				(font
					(size 1.016 1.016)
					(thickness 0.1524)
				)
				(justify mirror)
			)
		)
		(property "Device Type" "R402H16"
			(at -0.064008 -5.517896 180)
			(unlocked yes)
			(layer "B.Fab")
			(hide yes)
			(effects
				(font
					(size 1.016 1.016)
					(thickness 0.1524)
				)
				(justify mirror)
			)
		)
		(duplicate_pad_numbers_are_jumpers no)
		(fp_line
			(start 0.508 -0.9398)
			(end 0.508 0.9398)
			(stroke
				(width 0.1524)
				(type default)
			)
			(layer "B.SilkS")
		)
		(fp_line
			(start -0.508 -0.9398)
			(end 0.508 -0.9398)
			(stroke
				(width 0.1524)
				(type default)
			)
			(layer "B.SilkS")
		)
		(fp_rect
			(start 0.508 0.9398)
			(end -0.508 -0.9398)
			(stroke
				(width 0)
				(type default)
			)
			(fill no)
			(layer "B.CrtYd")
		)
		(fp_rect
			(start 0.508 0.9398)
			(end -0.508 -0.9398)
			(stroke
				(width 0)
				(type default)
			)
			(fill no)
			(layer "B.Fab")
		)
		(pad "1" smd custom
			(at 0 -0.4445)
			(size 0.1397 0.1397)
			(layers "B.Cu" "B.Mask" "B.Paste")
			(net "P3V3_STBY")
			(options
				(clearance outline)
				(anchor circle)
			)
			(primitives
				(gr_poly
					(pts
						(arc
							(start -0.1778 0.2794)
							(mid -0.249642 0.249642)
							(end -0.2794 0.1778)
						)
						(arc
							(start -0.2794 -0.1778)
							(mid -0.249642 -0.249642)
							(end -0.1778 -0.2794)
						)
						(arc
							(start 0.1778 -0.2794)
							(mid 0.249642 -0.249642)
							(end 0.2794 -0.1778)
						)
						(arc
							(start 0.2794 0.1778)
							(mid 0.249642 0.249642)
							(end 0.1778 0.2794)
						)
					)
					(width 0)
					(fill yes)
				)
			)
		)
		(pad "2" smd custom
			(at 0 0.4445)
			(size 0.1397 0.1397)
			(layers "B.Cu" "B.Mask" "B.Paste")
			(net "FM_BMC_RESET_N")
			(options
				(clearance outline)
				(anchor circle)
			)
			(primitives
				(gr_poly
					(pts
						(arc
							(start -0.1778 0.2794)
							(mid -0.249642 0.249642)
							(end -0.2794 0.1778)
						)
						(arc
							(start -0.2794 -0.1778)
							(mid -0.249642 -0.249642)
							(end -0.1778 -0.2794)
						)
						(arc
							(start 0.1778 -0.2794)
							(mid 0.249642 -0.249642)
							(end 0.2794 -0.1778)
						)
						(arc
							(start 0.2794 0.1778)
							(mid 0.249642 0.249642)
							(end 0.1778 0.2794)
						)
					)
					(width 0)
					(fill yes)
				)
			)
		)
	)
	(footprint ""
		(layer "B.Cu")
		(at 90.853006 -137.207752 -90)
		(property "Reference" "C504"
			(at 0 0 90)
			(layer "B.SilkS")
			(hide yes)
			(effects
				(font
					(size 1.27 1.27)
				)
				(justify mirror)
			)
		)
		(property "Value" "SCD1U16V2KX-3GP"
			(at -1.1811 -2.7051 270)
			(unlocked yes)
			(layer "B.Fab")
			(hide yes)
			(effects
				(font
					(size 1.016 1.016)
					(thickness 0.1524)
				)
				(justify mirror)
			)
		)
		(property "Device Type" "C402H22"
			(at -1.1811 -4.2291 270)
			(unlocked yes)
			(layer "B.Fab")
			(hide yes)
			(effects
				(font
					(size 1.016 1.016)
					(thickness 0.1524)
				)
				(justify mirror)
			)
		)
		(duplicate_pad_numbers_are_jumpers no)
		(fp_rect
			(start 0.4318 0.9525)
			(end -0.4318 -0.9525)
			(stroke
				(width 0)
				(type default)
			)
			(fill no)
			(layer "B.CrtYd")
		)
		(fp_rect
			(start 0.4318 0.9525)
			(end -0.4318 -0.9525)
			(stroke
				(width 0)
				(type default)
			)
			(fill no)
			(layer "B.Fab")
		)
		(pad "1" smd custom
			(at 0 -0.4445 90)
			(size 0.1524 0.1524)
			(layers "B.Cu" "B.Mask" "B.Paste")
			(net "P3V3_STBY")
			(options
				(clearance outline)
				(anchor circle)
			)
			(primitives
				(gr_poly
					(pts
						(arc
							(start 0.3048 0.2032)
							(mid 0.275042 0.275042)
							(end 0.2032 0.3048)
						)
						(arc
							(start -0.2032 0.3048)
							(mid -0.275042 0.275042)
							(end -0.3048 0.2032)
						)
						(arc
							(start -0.3048 -0.2032)
							(mid -0.275042 -0.275042)
							(end -0.2032 -0.3048)
						)
						(arc
							(start 0.2032 -0.3048)
							(mid 0.275042 -0.275042)
							(end 0.3048 -0.2032)
						)
					)
					(width 0)
					(fill yes)
				)
			)
		)
		(pad "2" smd custom
			(at 0 0.4445 90)
			(size 0.1524 0.1524)
			(layers "B.Cu" "B.Mask" "B.Paste")
			(net "GND")
			(options
				(clearance outline)
				(anchor circle)
			)
			(primitives
				(gr_poly
					(pts
						(arc
							(start 0.3048 0.2032)
							(mid 0.275042 0.275042)
							(end 0.2032 0.3048)
						)
						(arc
							(start -0.2032 0.3048)
							(mid -0.275042 0.275042)
							(end -0.3048 0.2032)
						)
						(arc
							(start -0.3048 -0.2032)
							(mid -0.275042 -0.275042)
							(end -0.2032 -0.3048)
						)
						(arc
							(start 0.2032 -0.3048)
							(mid 0.275042 -0.275042)
							(end 0.3048 -0.2032)
						)
					)
					(width 0)
					(fill yes)
				)
			)
		)
	)
	(footprint ""
		(layer "B.Cu")
		(at 30.897322 -156.547058 180)
		(property "Reference" "R782"
			(at 0 0 0)
			(layer "B.SilkS")
			(hide yes)
			(effects
				(font
					(size 1.27 1.27)
				)
				(justify mirror)
			)
		)
		(property "Value" "4K7R2F-GP"
			(at -0.064008 -3.993896 180)
			(unlocked yes)
			(layer "B.Fab")
			(hide yes)
			(effects
				(font
					(size 1.016 1.016)
					(thickness 0.1524)
				)
				(justify mirror)
			)
		)
		(property "Device Type" "R402H16"
			(at -0.064008 -5.517896 180)
			(unlocked yes)
			(layer "B.Fab")
			(hide yes)
			(effects
				(font
					(size 1.016 1.016)
					(thickness 0.1524)
				)
				(justify mirror)
			)
		)
		(duplicate_pad_numbers_are_jumpers no)
		(fp_line
			(start 0.508 -0.9398)
			(end 0.508 0.9398)
			(stroke
				(width 0.1524)
				(type default)
			)
			(layer "B.SilkS")
		)
		(fp_line
			(start -0.508 -0.9398)
			(end 0.508 -0.9398)
			(stroke
				(width 0.1524)
				(type default)
			)
			(layer "B.SilkS")
		)
		(fp_rect
			(start 0.508 0.9398)
			(end -0.508 -0.9398)
			(stroke
				(width 0)
				(type default)
			)
			(fill no)
			(layer "B.CrtYd")
		)
		(fp_rect
			(start 0.508 0.9398)
			(end -0.508 -0.9398)
			(stroke
				(width 0)
				(type default)
			)
			(fill no)
			(layer "B.Fab")
		)
		(pad "1" smd custom
			(at 0 -0.4445)
			(size 0.1397 0.1397)
			(layers "B.Cu" "B.Mask" "B.Paste")
			(net "COMP_FAST_THROTTLE_N")
			(options
				(clearance outline)
				(anchor circle)
			)
			(primitives
				(gr_poly
					(pts
						(arc
							(start -0.1778 0.2794)
							(mid -0.249642 0.249642)
							(end -0.2794 0.1778)
						)
						(arc
							(start -0.2794 -0.1778)
							(mid -0.249642 -0.249642)
							(end -0.1778 -0.2794)
						)
						(arc
							(start 0.1778 -0.2794)
							(mid 0.249642 -0.249642)
							(end 0.2794 -0.1778)
						)
						(arc
							(start 0.2794 0.1778)
							(mid 0.249642 0.249642)
							(end 0.1778 0.2794)
						)
					)
					(width 0)
					(fill yes)
				)
			)
		)
		(pad "2" smd custom
			(at 0 0.4445)
			(size 0.1397 0.1397)
			(layers "B.Cu" "B.Mask" "B.Paste")
			(net "GND")
			(options
				(clearance outline)
				(anchor circle)
			)
			(primitives
				(gr_poly
					(pts
						(arc
							(start -0.1778 0.2794)
							(mid -0.249642 0.249642)
							(end -0.2794 0.1778)
						)
						(arc
							(start -0.2794 -0.1778)
							(mid -0.249642 -0.249642)
							(end -0.1778 -0.2794)
						)
						(arc
							(start 0.1778 -0.2794)
							(mid 0.249642 -0.249642)
							(end 0.2794 -0.1778)
						)
						(arc
							(start 0.2794 0.1778)
							(mid 0.249642 0.249642)
							(end 0.1778 0.2794)
						)
					)
					(width 0)
					(fill yes)
				)
			)
		)
	)
	(footprint ""
		(layer "B.Cu")
		(at 172.071538 -120.580658)
		(property "Reference" "C617"
			(at 0 0 0)
			(layer "B.SilkS")
			(hide yes)
			(effects
				(font
					(size 1.27 1.27)
				)
				(justify mirror)
			)
		)
		(property "Value" "SC10U6D3V5KX-4GP"
			(at 0.0762 -6.1214 0)
			(unlocked yes)
			(layer "B.Fab")
			(hide yes)
			(effects
				(font
					(size 1.016 1.016)
					(thickness 0.1524)
				)
				(justify mirror)
			)
		)
		(property "Device Type" "C805H58"
			(at 0.0762 -8.1534 0)
			(unlocked yes)
			(layer "B.Fab")
			(hide yes)
			(effects
				(font
					(size 1.016 1.016)
					(thickness 0.1524)
				)
				(justify mirror)
			)
		)
		(duplicate_pad_numbers_are_jumpers no)
		(fp_line
			(start -0.635 0)
			(end 0.635 0)
			(stroke
				(width 0.508)
				(type default)
			)
			(layer "B.SilkS")
		)
		(fp_rect
			(start 0.9652 1.778)
			(end -0.9652 -1.778)
			(stroke
				(width 0)
				(type default)
			)
			(fill no)
			(layer "B.CrtYd")
		)
		(fp_poly
			(pts
				(xy 0.9652 -1.778) (xy -0.9652 -1.778) (xy -0.9652 1.778) (xy 0.9652 1.778)
			)
			(stroke
				(width 0)
				(type default)
			)
			(fill no)
			(layer "B.Fab")
		)
		(pad "1" smd rect
			(at 0 -0.9652 180)
			(size 1.397 1.143)
			(layers "B.Cu" "B.Mask" "B.Paste")
			(net "P3V3_M2")
		)
		(pad "2" smd rect
			(at 0 0.9652 180)
			(size 1.397 1.143)
			(layers "B.Cu" "B.Mask" "B.Paste")
			(net "GND")
		)
	)
)
